#ISCELL
  pure_quanta quanta_title_block_c *
  *
#ISCELL
  standard tap *
  page381_i10
#ISCELL
  standard tap *
  page381_i11
#ISCELL
  standard tap *
  page381_i12
#ISCELL
  standard tap *
  page381_i13
#ISCELL
  standard tap *
  page381_i14
#ISCELL
  standard tap *
  page381_i15
#ISCELL
  standard tap *
  page381_i16
#ISCELL
  standard tap *
  page381_i17
#ISCELL
  standard tap *
  page381_i18
#ISCELL
  standard tap *
  page381_i19
#ISCELL
  standard tap *
  page381_i20
#ISCELL
  standard offpage *
  page381_i21
#ISCELL
  standard offpage *
  page381_i22
#ISCELL
  standard tap *
  page381_i23
#ISCELL
  standard tap *
  page381_i24
#ISCELL
  standard offpage *
  page381_i25
#ISCELL
  standard offpage *
  page381_i26
#ISCELL
  standard tap *
  page381_i27
#ISCELL
  standard tap *
  page381_i28
#ISCELL
  standard tap *
  page381_i29
#CELL
  pure_quanta pt5161lrs *
  page381_i3
#ISCELL
  standard tap *
  page381_i30
#ISCELL
  standard tap *
  page381_i31
#ISCELL
  standard tap *
  page381_i32
#ISCELL
  standard tap *
  page381_i33
#ISCELL
  standard tap *
  page381_i34
#ISCELL
  standard tap *
  page381_i35
#ISCELL
  standard tap *
  page381_i36
#ISCELL
  standard tap *
  page381_i37
#ISCELL
  standard tap *
  page381_i38
#ISCELL
  standard tap *
  page381_i39
#CELL
  pure_quanta pt5161lrs *
  page381_i4
#ISCELL
  standard tap *
  page381_i40
#ISCELL
  standard tap *
  page381_i5
#ISCELL
  standard tap *
  page381_i6
#ISCELL
  standard tap *
  page381_i7
#ISCELL
  standard tap *
  page381_i8
#ISCELL
  standard tap *
  page381_i9
